# SCM (Grand Teton) — schematic netlist excerpt (pin names and nets, part order shuffled) for the footprints in the layout excerpt that follows; sources: Cadence DE-HDL packaged netlist, KiCad conversion of 12092022_DA0F0TMDCD0_F0T_Management_Board_D_brd_V3_OCP.brd

R5  Q_RES  1K 1% CHIP  pkg 0402LF  page 20 : A = PD_M_BMC_DDR4_TEN ; B = GND
C247  Q_CAP  0.1UF 25V 10% X7R  pkg 0402  page 41 : A = VCCIO0 ; B = GND

(kicad_pcb
	(version 20260206)
	(generator "pcbnew")
	(generator_version "10.0")
	(general
		(thickness 1.6)
		(legacy_teardrops no)
	)
	(paper "A4")
	(title_block
		(title "12092022_DA0F0TMDCD0_F0T_Management_Board_D_brd_V3_OCP.brd")
		(comment 1 "Grand Teton / footprints 1127-1128 of 1440")
	)
	(layers
		(0 "F.Cu" signal "TOP")
		(4 "In1.Cu" signal "GND")
		(6 "In2.Cu" signal "IN1")
		(8 "In3.Cu" signal "GND1")
		(10 "In4.Cu" signal "IN2")
		(12 "In5.Cu" signal "VCC")
		(14 "In6.Cu" signal "VCC1")
		(16 "In7.Cu" signal "IN3")
		(18 "In8.Cu" signal "GND2")
		(20 "In9.Cu" signal "IN4")
		(22 "In10.Cu" signal "GND3")
		(2 "B.Cu" signal "BOTTOM")
		(9 "F.Adhes" user "F.Adhesive")
		(11 "B.Adhes" user "B.Adhesive")
		(13 "F.Paste" user "Package Geometry/Pastemask Top")
		(15 "B.Paste" user "Package Geometry/Pastemask Bottom")
		(5 "F.SilkS" user "Ref Des/Silkscreen Top")
		(7 "B.SilkS" user "Ref Des/Silkscreen Bottom")
		(1 "F.Mask" user "Board Geometry/Soldermask Top")
		(3 "B.Mask" user "Board Geometry/Soldermask Bottom")
		(17 "Dwgs.User" user "User.Drawings")
		(19 "Cmts.User" user "User.Comments")
		(21 "Eco1.User" user "User.Eco1")
		(23 "Eco2.User" user "User.Eco2")
		(25 "Edge.Cuts" user "Board Geometry/Outline")
		(27 "Margin" user)
		(31 "F.CrtYd" user "Package Geometry/Place Bound Top")
		(29 "B.CrtYd" user "Package Geometry/Place Bound Bottom")
		(35 "F.Fab" user "Ref Des/Assembly Top")
		(33 "B.Fab" user "Ref Des/Assembly Bottom")
	)
	(footprint ""
		(layer "B.Cu")
		(at 18.259552 -89.98712 180)
		(property "Reference" "C247"
			(at 0 0 0)
			(layer "B.SilkS")
			(hide yes)
			(effects
				(font
					(size 1.27 1.27)
				)
				(justify mirror)
			)
		)
		(property "Value" ""
			(at 0 0 0)
			(layer "B.Fab")
			(effects
				(font
					(size 1.27 1.27)
				)
				(justify mirror)
			)
		)
		(duplicate_pad_numbers_are_jumpers no)
		(fp_line
			(start 0.69215 0.2921)
			(end 0.69215 -0.2921)
			(stroke
				(width 0.1524)
				(type default)
			)
			(layer "B.SilkS")
		)
		(fp_line
			(start 0.69215 -0.2921)
			(end -0.69215 -0.2921)
			(stroke
				(width 0.1524)
				(type default)
			)
			(layer "B.SilkS")
		)
		(fp_line
			(start -0.69215 0.2921)
			(end 0.69215 0.2921)
			(stroke
				(width 0.1524)
				(type default)
			)
			(layer "B.SilkS")
		)
		(fp_line
			(start -0.69215 -0.2921)
			(end -0.69215 0.2921)
			(stroke
				(width 0.1524)
				(type default)
			)
			(layer "B.SilkS")
		)
		(fp_line
			(start 0.51435 0.2794)
			(end 0.51435 -0.2794)
			(stroke
				(width 0.1)
				(type default)
			)
			(layer "B.Fab")
		)
		(fp_line
			(start 0.51435 -0.2794)
			(end -0.51435 -0.2794)
			(stroke
				(width 0.1)
				(type default)
			)
			(layer "B.Fab")
		)
		(fp_line
			(start -0.51435 0.2794)
			(end 0.51435 0.2794)
			(stroke
				(width 0.1)
				(type default)
			)
			(layer "B.Fab")
		)
		(fp_line
			(start -0.51435 -0.2794)
			(end -0.51435 0.2794)
			(stroke
				(width 0.1)
				(type default)
			)
			(layer "B.Fab")
		)
		(pad "1" smd circle
			(at 0.40005 0)
			(size 0 0)
			(layers "B.Cu" "B.Mask" "B.Paste")
			(net "VCCIO0")
		)
		(pad "2" smd circle
			(at -0.40005 0)
			(size 0 0)
			(layers "B.Cu" "B.Mask" "B.Paste")
			(net "GND")
		)
		(zone
			(layer "B.Cu")
			(hatch none 0.5)
			(connect_pads
				(clearance 0)
			)
			(min_thickness 0.25)
			(keepout
				(tracks not_allowed)
				(vias allowed)
				(pads allowed)
				(copperpour not_allowed)
				(footprints allowed)
			)
			(placement
				(enabled no)
				(sheetname "")
			)
			(fill
				(thermal_gap 0.5)
				(thermal_bridge_width 0.5)
				(island_removal_mode 0)
			)
			(polygon
				(pts
					(xy 18.069052 -90.07475) (xy 18.160492 -90.132916) (xy 18.359882 -90.132916) (xy 18.450052 -90.07475)
					(xy 18.450052 -89.89949) (xy 18.359882 -89.84107) (xy 18.160492 -89.84107) (xy 18.069052 -89.899236)
				)
			)
		)
	)
	(footprint ""
		(layer "B.Cu")
		(at 81.129886 -44.038012 180)
		(property "Reference" "R5"
			(at 0 0 0)
			(layer "B.SilkS")
			(hide yes)
			(effects
				(font
					(size 1.27 1.27)
				)
				(justify mirror)
			)
		)
		(property "Value" ""
			(at 0 0 0)
			(layer "B.Fab")
			(effects
				(font
					(size 1.27 1.27)
				)
				(justify mirror)
			)
		)
		(duplicate_pad_numbers_are_jumpers no)
		(fp_line
			(start 0.7874 0.4064)
			(end 0.7874 -0.4064)
			(stroke
				(width 0.1524)
				(type default)
			)
			(layer "B.SilkS")
		)
		(fp_line
			(start 0.7874 -0.4064)
			(end -0.7874 -0.4064)
			(stroke
				(width 0.1524)
				(type default)
			)
			(layer "B.SilkS")
		)
		(fp_line
			(start -0.7874 0.4064)
			(end 0.7874 0.4064)
			(stroke
				(width 0.1524)
				(type default)
			)
			(layer "B.SilkS")
		)
		(fp_line
			(start -0.7874 -0.4064)
			(end -0.7874 0.4064)
			(stroke
				(width 0.1524)
				(type default)
			)
			(layer "B.SilkS")
		)
		(fp_line
			(start 0.67945 0.3048)
			(end 0.67945 -0.305054)
			(stroke
				(width 0.1)
				(type default)
			)
			(layer "B.Fab")
		)
		(fp_line
			(start 0.67945 -0.305054)
			(end 0.12065 -0.305054)
			(stroke
				(width 0.1)
				(type default)
			)
			(layer "B.Fab")
		)
		(fp_line
			(start 0.12065 0.3048)
			(end 0.67945 0.3048)
			(stroke
				(width 0.1)
				(type default)
			)
			(layer "B.Fab")
		)
		(fp_line
			(start 0.12065 0.2794)
			(end 0.12065 0.3048)
			(stroke
				(width 0.1)
				(type default)
			)
			(layer "B.Fab")
		)
		(fp_line
			(start 0.12065 -0.2794)
			(end -0.12065 -0.2794)
			(stroke
				(width 0.1)
				(type default)
			)
			(layer "B.Fab")
		)
		(fp_line
			(start 0.12065 -0.305054)
			(end 0.12065 -0.2794)
			(stroke
				(width 0.1)
				(type default)
			)
			(layer "B.Fab")
		)
		(fp_line
			(start -0.120396 0.3048)
			(end -0.120396 0.2794)
			(stroke
				(width 0.1)
				(type default)
			)
			(layer "B.Fab")
		)
		(fp_line
			(start -0.120396 0.2794)
			(end 0.12065 0.2794)
			(stroke
				(width 0.1)
				(type default)
			)
			(layer "B.Fab")
		)
		(fp_line
			(start -0.12065 -0.2794)
			(end -0.12065 -0.3048)
			(stroke
				(width 0.1)
				(type default)
			)
			(layer "B.Fab")
		)
		(fp_line
			(start -0.12065 -0.3048)
			(end -0.67945 -0.3048)
			(stroke
				(width 0.1)
				(type default)
			)
			(layer "B.Fab")
		)
		(fp_line
			(start -0.67945 0.3048)
			(end -0.120396 0.3048)
			(stroke
				(width 0.1)
				(type default)
			)
			(layer "B.Fab")
		)
		(fp_line
			(start -0.67945 -0.3048)
			(end -0.67945 0.3048)
			(stroke
				(width 0.1)
				(type default)
			)
			(layer "B.Fab")
		)
		(pad "1" smd circle
			(at 0.40005 0)
			(size 0 0)
			(layers "B.Cu" "B.Mask" "B.Paste")
			(net "PD_M_BMC_DDR4_TEN")
		)
		(pad "2" smd circle
			(at -0.40005 0)
			(size 0 0)
			(layers "B.Cu" "B.Mask" "B.Paste")
			(net "GND")
		)
	)
)
